(kicad_pcb
	(version 20260206)
	(generator "pcbnew")
	(generator_version "10.0")
	(general
		(thickness 1.6)
		(legacy_teardrops no)
	)
	(paper "A4")
	(title_block
		(title "04192023_DAF0TMB3IC0_F0TG_MB_C_brd_V02_OCP.brd")
		(comment 1 "Grand Teton / footprints 933-939 of 8354")
	)
	(layers
		(0 "F.Cu" signal "TOP")
		(4 "In1.Cu" signal "GND")
		(6 "In2.Cu" signal "IN1")
		(8 "In3.Cu" signal "GND1")
		(10 "In4.Cu" signal "IN2")
		(12 "In5.Cu" signal "GND2")
		(14 "In6.Cu" signal "IN3")
		(16 "In7.Cu" signal "GND3")
		(18 "In8.Cu" signal "VCC")
		(20 "In9.Cu" signal "VCC1")
		(22 "In10.Cu" signal "GND4")
		(24 "In11.Cu" signal "IN4")
		(26 "In12.Cu" signal "GND5")
		(28 "In13.Cu" signal "IN5")
		(30 "In14.Cu" signal "GND6")
		(32 "In15.Cu" signal "IN6")
		(34 "In16.Cu" signal "GND7")
		(2 "B.Cu" signal "BOTTOM")
		(9 "F.Adhes" user "F.Adhesive")
		(11 "B.Adhes" user "B.Adhesive")
		(13 "F.Paste" user "Package Geometry/Pastemask Top")
		(15 "B.Paste" user "Package Geometry/Pastemask Bottom")
		(5 "F.SilkS" user "Ref Des/Silkscreen Top")
		(7 "B.SilkS" user "Ref Des/Silkscreen Bottom")
		(1 "F.Mask" user "Board Geometry/Soldermask Top")
		(3 "B.Mask" user "Board Geometry/Soldermask Bottom")
		(17 "Dwgs.User" user "User.Drawings")
		(19 "Cmts.User" user "User.Comments")
		(21 "Eco1.User" user "User.Eco1")
		(23 "Eco2.User" user "User.Eco2")
		(25 "Edge.Cuts" user "Board Geometry/Outline")
		(27 "Margin" user)
		(31 "F.CrtYd" user "Package Geometry/Place Bound Top")
		(29 "B.CrtYd" user "Package Geometry/Place Bound Bottom")
		(35 "F.Fab" user "Ref Des/Assembly Top")
		(33 "B.Fab" user "Ref Des/Assembly Bottom")
	)
	(footprint ""
		(layer "F.Cu")
		(at 110.565946 -54.882034 -90)
		(property "Reference" "R6308"
			(at 0 0 270)
			(layer "F.SilkS")
			(hide yes)
			(effects
				(font
					(size 1.27 1.27)
				)
			)
		)
		(property "Value" ""
			(at 0 0 270)
			(layer "F.Fab")
			(effects
				(font
					(size 1.27 1.27)
				)
			)
		)
		(duplicate_pad_numbers_are_jumpers no)
		(fp_line
			(start -0.7874 0.4064)
			(end -0.7874 -0.4064)
			(stroke
				(width 0.1524)
				(type default)
			)
			(layer "F.SilkS")
		)
		(fp_line
			(start 0.7874 0.4064)
			(end -0.7874 0.4064)
			(stroke
				(width 0.1524)
				(type default)
			)
			(layer "F.SilkS")
		)
		(fp_line
			(start -0.7874 -0.4064)
			(end 0.7874 -0.4064)
			(stroke
				(width 0.1524)
				(type default)
			)
			(layer "F.SilkS")
		)
		(fp_line
			(start 0.7874 -0.4064)
			(end 0.7874 0.4064)
			(stroke
				(width 0.1524)
				(type default)
			)
			(layer "F.SilkS")
		)
		(fp_line
			(start -0.67945 0.3048)
			(end -0.67945 -0.305054)
			(stroke
				(width 0.1)
				(type default)
			)
			(layer "F.Fab")
		)
		(fp_line
			(start -0.12065 0.3048)
			(end -0.67945 0.3048)
			(stroke
				(width 0.1)
				(type default)
			)
			(layer "F.Fab")
		)
		(fp_line
			(start 0.120396 0.3048)
			(end 0.120396 0.2794)
			(stroke
				(width 0.1)
				(type default)
			)
			(layer "F.Fab")
		)
		(fp_line
			(start 0.67945 0.3048)
			(end 0.120396 0.3048)
			(stroke
				(width 0.1)
				(type default)
			)
			(layer "F.Fab")
		)
		(fp_line
			(start -0.12065 0.2794)
			(end -0.12065 0.3048)
			(stroke
				(width 0.1)
				(type default)
			)
			(layer "F.Fab")
		)
		(fp_line
			(start 0.120396 0.2794)
			(end -0.12065 0.2794)
			(stroke
				(width 0.1)
				(type default)
			)
			(layer "F.Fab")
		)
		(fp_line
			(start -0.12065 -0.2794)
			(end 0.12065 -0.2794)
			(stroke
				(width 0.1)
				(type default)
			)
			(layer "F.Fab")
		)
		(fp_line
			(start 0.12065 -0.2794)
			(end 0.12065 -0.3048)
			(stroke
				(width 0.1)
				(type default)
			)
			(layer "F.Fab")
		)
		(fp_line
			(start 0.12065 -0.3048)
			(end 0.67945 -0.3048)
			(stroke
				(width 0.1)
				(type default)
			)
			(layer "F.Fab")
		)
		(fp_line
			(start 0.67945 -0.3048)
			(end 0.67945 0.3048)
			(stroke
				(width 0.1)
				(type default)
			)
			(layer "F.Fab")
		)
		(fp_line
			(start -0.67945 -0.305054)
			(end -0.12065 -0.305054)
			(stroke
				(width 0.1)
				(type default)
			)
			(layer "F.Fab")
		)
		(fp_line
			(start -0.12065 -0.305054)
			(end -0.12065 -0.2794)
			(stroke
				(width 0.1)
				(type default)
			)
			(layer "F.Fab")
		)
		(pad "1" smd circle
			(at -0.40005 0 270)
			(size 0 0)
			(layers "F.Cu" "F.Mask" "F.Paste")
			(net "P3V3_AUX")
		)
		(pad "2" smd circle
			(at 0.40005 0 270)
			(size 0 0)
			(layers "F.Cu" "F.Mask" "F.Paste")
			(net "USB_HUB2_MRP_CFG_NON_REM")
		)
	)
	(footprint ""
		(layer "F.Cu")
		(at 427.739048 -423.606214 -90)
		(property "Reference" "R6254"
			(at 0 0 270)
			(layer "F.SilkS")
			(hide yes)
			(effects
				(font
					(size 1.27 1.27)
				)
			)
		)
		(property "Value" ""
			(at 0 0 270)
			(layer "F.Fab")
			(effects
				(font
					(size 1.27 1.27)
				)
			)
		)
		(duplicate_pad_numbers_are_jumpers no)
		(fp_line
			(start -0.7874 0.4064)
			(end -0.7874 -0.4064)
			(stroke
				(width 0.1524)
				(type default)
			)
			(layer "F.SilkS")
		)
		(fp_line
			(start 0.7874 0.4064)
			(end -0.7874 0.4064)
			(stroke
				(width 0.1524)
				(type default)
			)
			(layer "F.SilkS")
		)
		(fp_line
			(start -0.7874 -0.4064)
			(end 0.7874 -0.4064)
			(stroke
				(width 0.1524)
				(type default)
			)
			(layer "F.SilkS")
		)
		(fp_line
			(start 0.7874 -0.4064)
			(end 0.7874 0.4064)
			(stroke
				(width 0.1524)
				(type default)
			)
			(layer "F.SilkS")
		)
		(fp_line
			(start -0.67945 0.3048)
			(end -0.67945 -0.305054)
			(stroke
				(width 0.1)
				(type default)
			)
			(layer "F.Fab")
		)
		(fp_line
			(start -0.12065 0.3048)
			(end -0.67945 0.3048)
			(stroke
				(width 0.1)
				(type default)
			)
			(layer "F.Fab")
		)
		(fp_line
			(start 0.120396 0.3048)
			(end 0.120396 0.2794)
			(stroke
				(width 0.1)
				(type default)
			)
			(layer "F.Fab")
		)
		(fp_line
			(start 0.67945 0.3048)
			(end 0.120396 0.3048)
			(stroke
				(width 0.1)
				(type default)
			)
			(layer "F.Fab")
		)
		(fp_line
			(start -0.12065 0.2794)
			(end -0.12065 0.3048)
			(stroke
				(width 0.1)
				(type default)
			)
			(layer "F.Fab")
		)
		(fp_line
			(start 0.120396 0.2794)
			(end -0.12065 0.2794)
			(stroke
				(width 0.1)
				(type default)
			)
			(layer "F.Fab")
		)
		(fp_line
			(start -0.12065 -0.2794)
			(end 0.12065 -0.2794)
			(stroke
				(width 0.1)
				(type default)
			)
			(layer "F.Fab")
		)
		(fp_line
			(start 0.12065 -0.2794)
			(end 0.12065 -0.3048)
			(stroke
				(width 0.1)
				(type default)
			)
			(layer "F.Fab")
		)
		(fp_line
			(start 0.12065 -0.3048)
			(end 0.67945 -0.3048)
			(stroke
				(width 0.1)
				(type default)
			)
			(layer "F.Fab")
		)
		(fp_line
			(start 0.67945 -0.3048)
			(end 0.67945 0.3048)
			(stroke
				(width 0.1)
				(type default)
			)
			(layer "F.Fab")
		)
		(fp_line
			(start -0.67945 -0.305054)
			(end -0.12065 -0.305054)
			(stroke
				(width 0.1)
				(type default)
			)
			(layer "F.Fab")
		)
		(fp_line
			(start -0.12065 -0.305054)
			(end -0.12065 -0.2794)
			(stroke
				(width 0.1)
				(type default)
			)
			(layer "F.Fab")
		)
		(pad "1" smd circle
			(at -0.40005 0 270)
			(size 0 0)
			(layers "F.Cu" "F.Mask" "F.Paste")
			(net "HSC_TYPE_ADC_A0")
		)
		(pad "2" smd circle
			(at 0.40005 0 270)
			(size 0 0)
			(layers "F.Cu" "F.Mask" "F.Paste")
			(net "SMB_HSC_TYPE_ADC_SDA")
		)
	)
	(footprint ""
		(layer "F.Cu")
		(at 412.487364 -143.967962 180)
		(property "Reference" "PC1846"
			(at 0 0 180)
			(layer "F.SilkS")
			(hide yes)
			(effects
				(font
					(size 1.27 1.27)
				)
			)
		)
		(property "Value" ""
			(at 0 0 180)
			(layer "F.Fab")
			(effects
				(font
					(size 1.27 1.27)
				)
			)
		)
		(duplicate_pad_numbers_are_jumpers no)
		(fp_line
			(start 0.7874 0.4064)
			(end -0.7874 0.4064)
			(stroke
				(width 0.1524)
				(type default)
			)
			(layer "F.SilkS")
		)
		(fp_line
			(start 0.7874 -0.4064)
			(end 0.7874 0.4064)
			(stroke
				(width 0.1524)
				(type default)
			)
			(layer "F.SilkS")
		)
		(fp_line
			(start -0.7874 0.4064)
			(end -0.7874 -0.4064)
			(stroke
				(width 0.1524)
				(type default)
			)
			(layer "F.SilkS")
		)
		(fp_line
			(start -0.7874 -0.4064)
			(end 0.7874 -0.4064)
			(stroke
				(width 0.1524)
				(type default)
			)
			(layer "F.SilkS")
		)
		(fp_line
			(start 0.67945 0.3048)
			(end 0.120396 0.3048)
			(stroke
				(width 0.1)
				(type default)
			)
			(layer "F.Fab")
		)
		(fp_line
			(start 0.67945 -0.3048)
			(end 0.67945 0.3048)
			(stroke
				(width 0.1)
				(type default)
			)
			(layer "F.Fab")
		)
		(fp_line
			(start 0.12065 -0.2794)
			(end 0.12065 -0.3048)
			(stroke
				(width 0.1)
				(type default)
			)
			(layer "F.Fab")
		)
		(fp_line
			(start 0.12065 -0.3048)
			(end 0.67945 -0.3048)
			(stroke
				(width 0.1)
				(type default)
			)
			(layer "F.Fab")
		)
		(fp_line
			(start 0.120396 0.3048)
			(end 0.120396 0.2794)
			(stroke
				(width 0.1)
				(type default)
			)
			(layer "F.Fab")
		)
		(fp_line
			(start 0.120396 0.2794)
			(end -0.12065 0.2794)
			(stroke
				(width 0.1)
				(type default)
			)
			(layer "F.Fab")
		)
		(fp_line
			(start -0.12065 0.3048)
			(end -0.67945 0.3048)
			(stroke
				(width 0.1)
				(type default)
			)
			(layer "F.Fab")
		)
		(fp_line
			(start -0.12065 0.2794)
			(end -0.12065 0.3048)
			(stroke
				(width 0.1)
				(type default)
			)
			(layer "F.Fab")
		)
		(fp_line
			(start -0.12065 -0.2794)
			(end 0.12065 -0.2794)
			(stroke
				(width 0.1)
				(type default)
			)
			(layer "F.Fab")
		)
		(fp_line
			(start -0.12065 -0.305054)
			(end -0.12065 -0.2794)
			(stroke
				(width 0.1)
				(type default)
			)
			(layer "F.Fab")
		)
		(fp_line
			(start -0.67945 0.3048)
			(end -0.67945 -0.305054)
			(stroke
				(width 0.1)
				(type default)
			)
			(layer "F.Fab")
		)
		(fp_line
			(start -0.67945 -0.305054)
			(end -0.12065 -0.305054)
			(stroke
				(width 0.1)
				(type default)
			)
			(layer "F.Fab")
		)
		(pad "1" smd circle
			(at -0.40005 0 180)
			(size 0 0)
			(layers "F.Cu" "F.Mask" "F.Paste")
			(net "SW_P5V_AUX_FLT")
		)
		(pad "2" smd circle
			(at 0.40005 0 180)
			(size 0 0)
			(layers "F.Cu" "F.Mask" "F.Paste")
			(net "GND")
		)
	)
	(footprint ""
		(layer "F.Cu")
		(at 223.774 -80.137 -90)
		(property "Reference" "U8003"
			(at 1.93294 -2.871978 90)
			(unlocked yes)
			(layer "F.SilkS")
			(effects
				(font
					(size 0.7874 0.5842)
					(thickness 0.1524)
				)
				(justify left)
			)
		)
		(property "Value" ""
			(at 0 0 270)
			(layer "F.Fab")
			(effects
				(font
					(size 1.27 1.27)
				)
			)
		)
		(duplicate_pad_numbers_are_jumpers no)
		(fp_line
			(start -1.759712 1.500124)
			(end -1.759712 -1.500124)
			(stroke
				(width 0.1524)
				(type default)
			)
			(layer "F.SilkS")
		)
		(fp_line
			(start 1.759712 1.500124)
			(end -1.759712 1.500124)
			(stroke
				(width 0.1524)
				(type default)
			)
			(layer "F.SilkS")
		)
		(fp_line
			(start -1.759712 -1.500124)
			(end 1.759712 -1.500124)
			(stroke
				(width 0.1524)
				(type default)
			)
			(layer "F.SilkS")
		)
		(fp_line
			(start 1.759712 -1.500124)
			(end 1.759712 1.500124)
			(stroke
				(width 0.1524)
				(type default)
			)
			(layer "F.SilkS")
		)
		(fp_line
			(start -0.700024 1.500124)
			(end -0.700024 -1.500124)
			(stroke
				(width 0.1)
				(type default)
			)
			(layer "F.Fab")
		)
		(fp_line
			(start 0.700024 1.500124)
			(end -0.700024 1.500124)
			(stroke
				(width 0.1)
				(type default)
			)
			(layer "F.Fab")
		)
		(fp_line
			(start -0.700024 -1.500124)
			(end 0.700024 -1.500124)
			(stroke
				(width 0.1)
				(type default)
			)
			(layer "F.Fab")
		)
		(fp_line
			(start 0.700024 -1.500124)
			(end 0.700024 1.500124)
			(stroke
				(width 0.1)
				(type default)
			)
			(layer "F.Fab")
		)
		(pad "1" smd rect
			(at -1.150112 -0.94996 180)
			(size 0.6604 0.9652)
			(layers "F.Cu" "F.Mask" "F.Paste")
			(net "GND")
		)
		(pad "2" smd rect
			(at -1.150112 0.94996 180)
			(size 0.6604 0.9652)
			(layers "F.Cu" "F.Mask" "F.Paste")
			(net "P3V3_E1S_PWRGD_0_R1")
		)
		(pad "3" smd rect
			(at 1.150112 0 180)
			(size 0.6604 0.9652)
			(layers "F.Cu" "F.Mask" "F.Paste")
			(net "P3V3_E1S_0_R")
		)
	)
	(footprint ""
		(layer "F.Cu")
		(at 328.487278 -339.63991 -90)
		(property "Reference" "PC94"
			(at 0 0 270)
			(layer "F.SilkS")
			(hide yes)
			(effects
				(font
					(size 1.27 1.27)
				)
			)
		)
		(property "Value" ""
			(at 0 0 270)
			(layer "F.Fab")
			(effects
				(font
					(size 1.27 1.27)
				)
			)
		)
		(duplicate_pad_numbers_are_jumpers no)
		(fp_line
			(start -0.7874 0.4064)
			(end -0.7874 -0.4064)
			(stroke
				(width 0.1524)
				(type default)
			)
			(layer "F.SilkS")
		)
		(fp_line
			(start 0.7874 0.4064)
			(end -0.7874 0.4064)
			(stroke
				(width 0.1524)
				(type default)
			)
			(layer "F.SilkS")
		)
		(fp_line
			(start -0.7874 -0.4064)
			(end 0.7874 -0.4064)
			(stroke
				(width 0.1524)
				(type default)
			)
			(layer "F.SilkS")
		)
		(fp_line
			(start 0.7874 -0.4064)
			(end 0.7874 0.4064)
			(stroke
				(width 0.1524)
				(type default)
			)
			(layer "F.SilkS")
		)
		(fp_line
			(start -0.67945 0.3048)
			(end -0.67945 -0.305054)
			(stroke
				(width 0.1)
				(type default)
			)
			(layer "F.Fab")
		)
		(fp_line
			(start -0.12065 0.3048)
			(end -0.67945 0.3048)
			(stroke
				(width 0.1)
				(type default)
			)
			(layer "F.Fab")
		)
		(fp_line
			(start 0.120396 0.3048)
			(end 0.120396 0.2794)
			(stroke
				(width 0.1)
				(type default)
			)
			(layer "F.Fab")
		)
		(fp_line
			(start 0.67945 0.3048)
			(end 0.120396 0.3048)
			(stroke
				(width 0.1)
				(type default)
			)
			(layer "F.Fab")
		)
		(fp_line
			(start -0.12065 0.2794)
			(end -0.12065 0.3048)
			(stroke
				(width 0.1)
				(type default)
			)
			(layer "F.Fab")
		)
		(fp_line
			(start 0.120396 0.2794)
			(end -0.12065 0.2794)
			(stroke
				(width 0.1)
				(type default)
			)
			(layer "F.Fab")
		)
		(fp_line
			(start -0.12065 -0.2794)
			(end 0.12065 -0.2794)
			(stroke
				(width 0.1)
				(type default)
			)
			(layer "F.Fab")
		)
		(fp_line
			(start 0.12065 -0.2794)
			(end 0.12065 -0.3048)
			(stroke
				(width 0.1)
				(type default)
			)
			(layer "F.Fab")
		)
		(fp_line
			(start 0.12065 -0.3048)
			(end 0.67945 -0.3048)
			(stroke
				(width 0.1)
				(type default)
			)
			(layer "F.Fab")
		)
		(fp_line
			(start 0.67945 -0.3048)
			(end 0.67945 0.3048)
			(stroke
				(width 0.1)
				(type default)
			)
			(layer "F.Fab")
		)
		(fp_line
			(start -0.67945 -0.305054)
			(end -0.12065 -0.305054)
			(stroke
				(width 0.1)
				(type default)
			)
			(layer "F.Fab")
		)
		(fp_line
			(start -0.12065 -0.305054)
			(end -0.12065 -0.2794)
			(stroke
				(width 0.1)
				(type default)
			)
			(layer "F.Fab")
		)
		(pad "1" smd circle
			(at -0.40005 0 270)
			(size 0 0)
			(layers "F.Cu" "F.Mask" "F.Paste")
			(net "SW_PVDDCR_CPU1_P0_BOOT2_R")
		)
		(pad "2" smd circle
			(at 0.40005 0 270)
			(size 0 0)
			(layers "F.Cu" "F.Mask" "F.Paste")
			(net "SW_PVDDCR_CPU1_P0_BOOTR2")
		)
	)
	(footprint ""
		(layer "F.Cu")
		(at 104.409748 -386.7912 90)
		(property "Reference" "R741"
			(at 0 0 90)
			(layer "F.SilkS")
			(hide yes)
			(effects
				(font
					(size 1.27 1.27)
				)
			)
		)
		(property "Value" ""
			(at 0 0 90)
			(layer "F.Fab")
			(effects
				(font
					(size 1.27 1.27)
				)
			)
		)
		(duplicate_pad_numbers_are_jumpers no)
		(fp_line
			(start 0.32512 -0.175006)
			(end 0.32512 0.175006)
			(stroke
				(width 0.1)
				(type default)
			)
			(layer "F.Fab")
		)
		(fp_line
			(start -0.32512 -0.175006)
			(end 0.32512 -0.175006)
			(stroke
				(width 0.1)
				(type default)
			)
			(layer "F.Fab")
		)
		(fp_line
			(start 0.32512 0.175006)
			(end -0.32512 0.175006)
			(stroke
				(width 0.1)
				(type default)
			)
			(layer "F.Fab")
		)
		(fp_line
			(start -0.32512 0.175006)
			(end -0.32512 -0.175006)
			(stroke
				(width 0.1)
				(type default)
			)
			(layer "F.Fab")
		)
		(pad "1" smd rect
			(at -0.2667 0 90)
			(size 0.3048 0.381)
			(layers "F.Cu" "F.Mask" "F.Paste")
			(net "RT_CPU1_P1_ADDR3")
		)
		(pad "2" smd rect
			(at 0.2667 0 270)
			(size 0.3048 0.381)
			(layers "F.Cu" "F.Mask" "F.Paste")
			(net "GND")
		)
	)
	(footprint ""
		(layer "F.Cu")
		(at 83.439254 -334.976724 -90)
		(property "Reference" "PC371_C1P1_1"
			(at 0 0 270)
			(layer "F.SilkS")
			(hide yes)
			(effects
				(font
					(size 1.27 1.27)
				)
			)
		)
		(property "Value" ""
			(at 0 0 270)
			(layer "F.Fab")
			(effects
				(font
					(size 1.27 1.27)
				)
			)
		)
		(duplicate_pad_numbers_are_jumpers no)
		(fp_line
			(start -0.7874 0.4064)
			(end -0.7874 -0.4064)
			(stroke
				(width 0.1524)
				(type default)
			)
			(layer "F.SilkS")
		)
		(fp_line
			(start 0.7874 0.4064)
			(end -0.7874 0.4064)
			(stroke
				(width 0.1524)
				(type default)
			)
			(layer "F.SilkS")
		)
		(fp_line
			(start -0.7874 -0.4064)
			(end 0.7874 -0.4064)
			(stroke
				(width 0.1524)
				(type default)
			)
			(layer "F.SilkS")
		)
		(fp_line
			(start 0.7874 -0.4064)
			(end 0.7874 0.4064)
			(stroke
				(width 0.1524)
				(type default)
			)
			(layer "F.SilkS")
		)
		(fp_line
			(start -0.67945 0.3048)
			(end -0.67945 -0.305054)
			(stroke
				(width 0.1)
				(type default)
			)
			(layer "F.Fab")
		)
		(fp_line
			(start -0.12065 0.3048)
			(end -0.67945 0.3048)
			(stroke
				(width 0.1)
				(type default)
			)
			(layer "F.Fab")
		)
		(fp_line
			(start 0.120396 0.3048)
			(end 0.120396 0.2794)
			(stroke
				(width 0.1)
				(type default)
			)
			(layer "F.Fab")
		)
		(fp_line
			(start 0.67945 0.3048)
			(end 0.120396 0.3048)
			(stroke
				(width 0.1)
				(type default)
			)
			(layer "F.Fab")
		)
		(fp_line
			(start -0.12065 0.2794)
			(end -0.12065 0.3048)
			(stroke
				(width 0.1)
				(type default)
			)
			(layer "F.Fab")
		)
		(fp_line
			(start 0.120396 0.2794)
			(end -0.12065 0.2794)
			(stroke
				(width 0.1)
				(type default)
			)
			(layer "F.Fab")
		)
		(fp_line
			(start -0.12065 -0.2794)
			(end 0.12065 -0.2794)
			(stroke
				(width 0.1)
				(type default)
			)
			(layer "F.Fab")
		)
		(fp_line
			(start 0.12065 -0.2794)
			(end 0.12065 -0.3048)
			(stroke
				(width 0.1)
				(type default)
			)
			(layer "F.Fab")
		)
		(fp_line
			(start 0.12065 -0.3048)
			(end 0.67945 -0.3048)
			(stroke
				(width 0.1)
				(type default)
			)
			(layer "F.Fab")
		)
		(fp_line
			(start 0.67945 -0.3048)
			(end 0.67945 0.3048)
			(stroke
				(width 0.1)
				(type default)
			)
			(layer "F.Fab")
		)
		(fp_line
			(start -0.67945 -0.305054)
			(end -0.12065 -0.305054)
			(stroke
				(width 0.1)
				(type default)
			)
			(layer "F.Fab")
		)
		(fp_line
			(start -0.12065 -0.305054)
			(end -0.12065 -0.2794)
			(stroke
				(width 0.1)
				(type default)
			)
			(layer "F.Fab")
		)
		(pad "1" smd circle
			(at -0.40005 0 270)
			(size 0 0)
			(layers "F.Cu" "F.Mask" "F.Paste")
			(net "PVDDCR_CPU1_P1_PVCC")
		)
		(pad "2" smd circle
			(at 0.40005 0 270)
			(size 0 0)
			(layers "F.Cu" "F.Mask" "F.Paste")
			(net "GND")
		)
	)
)
